# TIMECARD (Time Appliance Project (Time Card)) — schematic netlist excerpt (pin names and nets, part order shuffled) for the footprints in the layout excerpt that follows; sources: Cadence DE-HDL packaged netlist, KiCad conversion of R4006-B0001-02_R01.brd

C209  CAPACITOR  0.1UF 10V 10%  pkg SMC_0402R_H022  page 14 : \1\ = FPGA_MGTAVTT ; \2\ = SG
C136  CAPACITOR  0.1UF 10V 10%  pkg SMC_0402R_H022  page 14 : \1\ = XP1R2V_FPGA ; \2\ = SG

(kicad_pcb
	(version 20260206)
	(generator "pcbnew")
	(generator_version "10.0")
	(general
		(thickness 1.6)
		(legacy_teardrops no)
	)
	(paper "A4")
	(title_block
		(title "timecard-production-celestica-r4006 — R4006-B0001-02_R01.brd")
		(comment 1 "Time Appliance Project (Time Card) / footprints 687-688 of 1113")
	)
	(layers
		(0 "F.Cu" signal "TOP")
		(4 "In1.Cu" signal "L02_GND1")
		(6 "In2.Cu" signal "L03_SIG1")
		(8 "In3.Cu" signal "L04_GND2")
		(10 "In4.Cu" signal "L05_VCC1")
		(12 "In5.Cu" signal "L06_VCC2")
		(14 "In6.Cu" signal "L07_GND3")
		(16 "In7.Cu" signal "L08_SIG2")
		(18 "In8.Cu" signal "L09_GND4")
		(2 "B.Cu" signal "BOTTOM")
		(9 "F.Adhes" user "F.Adhesive")
		(11 "B.Adhes" user "B.Adhesive")
		(13 "F.Paste" user "Package Geometry/Pastemask Top")
		(15 "B.Paste" user "Package Geometry/Pastemask Bottom")
		(5 "F.SilkS" user "Ref Des/Silkscreen Top")
		(7 "B.SilkS" user "Ref Des/Silkscreen Bottom")
		(1 "F.Mask" user "Board Geometry/Soldermask Top")
		(3 "B.Mask" user "Board Geometry/Soldermask Bottom")
		(17 "Dwgs.User" user "User.Drawings")
		(19 "Cmts.User" user "User.Comments")
		(21 "Eco1.User" user "User.Eco1")
		(23 "Eco2.User" user "User.Eco2")
		(25 "Edge.Cuts" user "Board Geometry/Outline")
		(27 "Margin" user)
		(31 "F.CrtYd" user "Package Geometry/Place Bound Top")
		(29 "B.CrtYd" user "Package Geometry/Place Bound Bottom")
		(35 "F.Fab" user "Ref Des/Assembly Top")
		(33 "B.Fab" user "Ref Des/Assembly Bottom")
	)
	(footprint ""
		(layer "B.Cu")
		(at 100.347018 -41.823132 180)
		(property "Reference" "C209"
			(at 42.435018 -1.214882 0)
			(unlocked yes)
			(layer "B.SilkS")
			(effects
				(font
					(size 0.635 0.4064)
					(thickness 0.1524)
				)
				(justify mirror)
			)
		)
		(property "Value" "VAL*"
			(at 0 3.718306 180)
			(unlocked yes)
			(layer "B.Fab")
			(hide yes)
			(effects
				(font
					(size 0.7874 0.5842)
					(thickness 0.127)
				)
				(justify mirror)
			)
		)
		(property "Tolerance" "TOL*"
			(at 0 4.861306 180)
			(unlocked yes)
			(layer "Cmts.User")
			(hide yes)
			(effects
				(font
					(size 0.7874 0.5842)
					(thickness 0.127)
				)
				(justify mirror)
			)
		)
		(property "User Part Number" "PARTNUM*"
			(at 0 2.575306 180)
			(unlocked yes)
			(layer "Cmts.User")
			(hide yes)
			(effects
				(font
					(size 0.7874 0.5842)
					(thickness 0.127)
				)
				(justify mirror)
			)
		)
		(property "Device Type" "CAPACITOR-G105-0B104-CK,0.1UF,A"
			(at 0 1.432306 180)
			(unlocked yes)
			(layer "B.Fab")
			(hide yes)
			(effects
				(font
					(size 0.7874 0.5842)
					(thickness 0.127)
				)
				(justify mirror)
			)
		)
		(duplicate_pad_numbers_are_jumpers no)
		(fp_line
			(start 0.970026 0.4699)
			(end 0.970026 -0.4699)
			(stroke
				(width 0.1)
				(type default)
			)
			(layer "B.SilkS")
		)
		(fp_line
			(start 0.970026 -0.4699)
			(end -0.970026 -0.4699)
			(stroke
				(width 0.1)
				(type default)
			)
			(layer "B.SilkS")
		)
		(fp_line
			(start -0.970026 0.4699)
			(end 0.970026 0.4699)
			(stroke
				(width 0.1)
				(type default)
			)
			(layer "B.SilkS")
		)
		(fp_line
			(start -0.970026 -0.4699)
			(end -0.970026 0.4699)
			(stroke
				(width 0.1)
				(type default)
			)
			(layer "B.SilkS")
		)
		(fp_poly
			(pts
				(xy 0.970026 0.4699) (xy -0.970026 0.4699) (xy -0.970026 -0.4699) (xy 0.970026 -0.4699)
			)
			(stroke
				(width 0)
				(type default)
			)
			(fill no)
			(layer "B.CrtYd")
		)
		(fp_line
			(start 0.508 0.3048)
			(end 0.508 -0.3048)
			(stroke
				(width 0.1)
				(type default)
			)
			(layer "B.Fab")
		)
		(fp_line
			(start 0.508 -0.3048)
			(end -0.508 -0.3048)
			(stroke
				(width 0.1)
				(type default)
			)
			(layer "B.Fab")
		)
		(fp_line
			(start -0.508 0.3048)
			(end 0.508 0.3048)
			(stroke
				(width 0.1)
				(type default)
			)
			(layer "B.Fab")
		)
		(fp_line
			(start -0.508 -0.3048)
			(end -0.508 0.3048)
			(stroke
				(width 0.1)
				(type default)
			)
			(layer "B.Fab")
		)
		(pad "1" smd circle
			(at 0.500126 0)
			(size 0.635 0.635)
			(layers "B.Cu" "B.Mask" "B.Paste")
			(net "FPGA_MGTAVTT")
		)
		(pad "2" smd circle
			(at -0.500126 0)
			(size 0.635 0.635)
			(layers "B.Cu" "B.Mask" "B.Paste")
			(net "SG")
		)
	)
	(footprint ""
		(layer "B.Cu")
		(at 89.408 -34.417 90)
		(property "Reference" "C136"
			(at -3.937 0.10033 270)
			(unlocked yes)
			(layer "B.SilkS")
			(effects
				(font
					(size 0.7874 0.5842)
					(thickness 0.1524)
				)
				(justify mirror)
			)
		)
		(property "Value" "VAL*"
			(at -0.0762 2.067306 90)
			(unlocked yes)
			(layer "B.Fab")
			(hide yes)
			(effects
				(font
					(size 0.7874 0.5842)
					(thickness 0.1524)
				)
				(justify mirror)
			)
		)
		(property "Tolerance" "TOL*"
			(at -0.0762 3.032506 90)
			(unlocked yes)
			(layer "Cmts.User")
			(hide yes)
			(effects
				(font
					(size 0.7874 0.5842)
					(thickness 0.1524)
				)
				(justify mirror)
			)
		)
		(property "User Part Number" "PARTNUM*"
			(at -0.1016 4.023106 90)
			(unlocked yes)
			(layer "Cmts.User")
			(hide yes)
			(effects
				(font
					(size 0.7874 0.5842)
					(thickness 0.1524)
				)
				(justify mirror)
			)
		)
		(property "Device Type" "CAPACITOR-G105-0B104-CK,0.1UF,A"
			(at -0.0508 1.127506 90)
			(unlocked yes)
			(layer "B.Fab")
			(hide yes)
			(effects
				(font
					(size 0.7874 0.5842)
					(thickness 0.1524)
				)
				(justify mirror)
			)
		)
		(duplicate_pad_numbers_are_jumpers no)
		(fp_line
			(start 1.143 -0.5588)
			(end 1.143 0.5588)
			(stroke
				(width 0.1)
				(type default)
			)
			(layer "B.SilkS")
		)
		(fp_line
			(start -1.143 -0.5588)
			(end 1.143 -0.5588)
			(stroke
				(width 0.1)
				(type default)
			)
			(layer "B.SilkS")
		)
		(fp_line
			(start 1.143 0.5588)
			(end -1.143 0.5588)
			(stroke
				(width 0.1)
				(type default)
			)
			(layer "B.SilkS")
		)
		(fp_line
			(start -1.143 0.5588)
			(end -1.143 -0.5588)
			(stroke
				(width 0.1)
				(type default)
			)
			(layer "B.SilkS")
		)
		(fp_rect
			(start 1.143 0.5588)
			(end -1.143 -0.5588)
			(stroke
				(width 0)
				(type default)
			)
			(fill no)
			(layer "B.CrtYd")
		)
		(fp_line
			(start 0.508 -0.3048)
			(end 0.508 0.3048)
			(stroke
				(width 0.1)
				(type default)
			)
			(layer "B.Fab")
		)
		(fp_line
			(start -0.508 -0.3048)
			(end 0.508 -0.3048)
			(stroke
				(width 0.1)
				(type default)
			)
			(layer "B.Fab")
		)
		(fp_line
			(start 0.508 0.3048)
			(end -0.508 0.3048)
			(stroke
				(width 0.1)
				(type default)
			)
			(layer "B.Fab")
		)
		(fp_line
			(start -0.508 0.3048)
			(end -0.508 -0.3048)
			(stroke
				(width 0.1)
				(type default)
			)
			(layer "B.Fab")
		)
		(pad "1" smd rect
			(at 0.5334 0 270)
			(size 0.7112 0.6096)
			(layers "B.Cu" "B.Mask" "B.Paste")
			(net "XP1R2V_FPGA")
		)
		(pad "2" smd rect
			(at -0.5334 0 270)
			(size 0.7112 0.6096)
			(layers "B.Cu" "B.Mask" "B.Paste")
			(net "SG")
		)
		(zone
			(layer "B.Cu")
			(hatch none 0.5)
			(connect_pads
				(clearance 0)
			)
			(min_thickness 0.25)
			(keepout
				(tracks allowed)
				(vias not_allowed)
				(pads allowed)
				(copperpour not_allowed)
				(footprints allowed)
			)
			(placement
				(enabled no)
				(sheetname "")
			)
			(fill
				(thermal_gap 0.5)
				(thermal_bridge_width 0.5)
				(island_removal_mode 0)
			)
			(polygon
				(pts
					(xy 89.7128 -34.4932) (xy 89.1032 -34.4932) (xy 89.1032 -34.3408) (xy 89.7128 -34.3408)
				)
			)
		)
	)
)
